# T6G (Grand Teton) — schematic netlist excerpt (pin names and nets, part order shuffled) for the footprints in the layout excerpt that follows; sources: Cadence DE-HDL packaged netlist, KiCad conversion of 04192023_DAF0TMB3IC0_F0TG_MB_C_brd_V02_OCP.brd

R6231  Q_RES  2.2K 5% CHIP  pkg 0402LF  page 267 : A = P3V3_AUX ; B = SMB_P12V_HSC_SCL
PC2223  Q_CAP  1UF 25V 10% X6S  pkg C0402  page 264 : A = HSC_VDD_R_4 ; B = AGND_HSC

(kicad_pcb
	(version 20260206)
	(generator "pcbnew")
	(generator_version "10.0")
	(general
		(thickness 1.6)
		(legacy_teardrops no)
	)
	(paper "A4")
	(title_block
		(title "04192023_DAF0TMB3IC0_F0TG_MB_C_brd_V02_OCP.brd")
		(comment 1 "Grand Teton / footprints 3512-3513 of 8354")
	)
	(layers
		(0 "F.Cu" signal "TOP")
		(4 "In1.Cu" signal "GND")
		(6 "In2.Cu" signal "IN1")
		(8 "In3.Cu" signal "GND1")
		(10 "In4.Cu" signal "IN2")
		(12 "In5.Cu" signal "GND2")
		(14 "In6.Cu" signal "IN3")
		(16 "In7.Cu" signal "GND3")
		(18 "In8.Cu" signal "VCC")
		(20 "In9.Cu" signal "VCC1")
		(22 "In10.Cu" signal "GND4")
		(24 "In11.Cu" signal "IN4")
		(26 "In12.Cu" signal "GND5")
		(28 "In13.Cu" signal "IN5")
		(30 "In14.Cu" signal "GND6")
		(32 "In15.Cu" signal "IN6")
		(34 "In16.Cu" signal "GND7")
		(2 "B.Cu" signal "BOTTOM")
		(9 "F.Adhes" user "F.Adhesive")
		(11 "B.Adhes" user "B.Adhesive")
		(13 "F.Paste" user "Package Geometry/Pastemask Top")
		(15 "B.Paste" user "Package Geometry/Pastemask Bottom")
		(5 "F.SilkS" user "Ref Des/Silkscreen Top")
		(7 "B.SilkS" user "Ref Des/Silkscreen Bottom")
		(1 "F.Mask" user "Board Geometry/Soldermask Top")
		(3 "B.Mask" user "Board Geometry/Soldermask Bottom")
		(17 "Dwgs.User" user "User.Drawings")
		(19 "Cmts.User" user "User.Comments")
		(21 "Eco1.User" user "User.Eco1")
		(23 "Eco2.User" user "User.Eco2")
		(25 "Edge.Cuts" user "Board Geometry/Outline")
		(27 "Margin" user)
		(31 "F.CrtYd" user "Package Geometry/Place Bound Top")
		(29 "B.CrtYd" user "Package Geometry/Place Bound Bottom")
		(35 "F.Fab" user "Ref Des/Assembly Top")
		(33 "B.Fab" user "Ref Des/Assembly Bottom")
	)
	(footprint ""
		(layer "F.Cu")
		(at 283.112718 -388.71652 90)
		(property "Reference" "R6231"
			(at 0 0 90)
			(layer "F.SilkS")
			(hide yes)
			(effects
				(font
					(size 1.27 1.27)
				)
			)
		)
		(property "Value" ""
			(at 0 0 90)
			(layer "F.Fab")
			(effects
				(font
					(size 1.27 1.27)
				)
			)
		)
		(duplicate_pad_numbers_are_jumpers no)
		(fp_line
			(start 0.7874 -0.4064)
			(end 0.7874 0.4064)
			(stroke
				(width 0.1524)
				(type default)
			)
			(layer "F.SilkS")
		)
		(fp_line
			(start -0.7874 -0.4064)
			(end 0.7874 -0.4064)
			(stroke
				(width 0.1524)
				(type default)
			)
			(layer "F.SilkS")
		)
		(fp_line
			(start 0.7874 0.4064)
			(end -0.7874 0.4064)
			(stroke
				(width 0.1524)
				(type default)
			)
			(layer "F.SilkS")
		)
		(fp_line
			(start -0.7874 0.4064)
			(end -0.7874 -0.4064)
			(stroke
				(width 0.1524)
				(type default)
			)
			(layer "F.SilkS")
		)
		(fp_line
			(start -0.12065 -0.305054)
			(end -0.12065 -0.2794)
			(stroke
				(width 0.1)
				(type default)
			)
			(layer "F.Fab")
		)
		(fp_line
			(start -0.67945 -0.305054)
			(end -0.12065 -0.305054)
			(stroke
				(width 0.1)
				(type default)
			)
			(layer "F.Fab")
		)
		(fp_line
			(start 0.67945 -0.3048)
			(end 0.67945 0.3048)
			(stroke
				(width 0.1)
				(type default)
			)
			(layer "F.Fab")
		)
		(fp_line
			(start 0.12065 -0.3048)
			(end 0.67945 -0.3048)
			(stroke
				(width 0.1)
				(type default)
			)
			(layer "F.Fab")
		)
		(fp_line
			(start 0.12065 -0.2794)
			(end 0.12065 -0.3048)
			(stroke
				(width 0.1)
				(type default)
			)
			(layer "F.Fab")
		)
		(fp_line
			(start -0.12065 -0.2794)
			(end 0.12065 -0.2794)
			(stroke
				(width 0.1)
				(type default)
			)
			(layer "F.Fab")
		)
		(fp_line
			(start 0.120396 0.2794)
			(end -0.12065 0.2794)
			(stroke
				(width 0.1)
				(type default)
			)
			(layer "F.Fab")
		)
		(fp_line
			(start -0.12065 0.2794)
			(end -0.12065 0.3048)
			(stroke
				(width 0.1)
				(type default)
			)
			(layer "F.Fab")
		)
		(fp_line
			(start 0.67945 0.3048)
			(end 0.120396 0.3048)
			(stroke
				(width 0.1)
				(type default)
			)
			(layer "F.Fab")
		)
		(fp_line
			(start 0.120396 0.3048)
			(end 0.120396 0.2794)
			(stroke
				(width 0.1)
				(type default)
			)
			(layer "F.Fab")
		)
		(fp_line
			(start -0.12065 0.3048)
			(end -0.67945 0.3048)
			(stroke
				(width 0.1)
				(type default)
			)
			(layer "F.Fab")
		)
		(fp_line
			(start -0.67945 0.3048)
			(end -0.67945 -0.305054)
			(stroke
				(width 0.1)
				(type default)
			)
			(layer "F.Fab")
		)
		(pad "1" smd circle
			(at -0.40005 0 90)
			(size 0 0)
			(layers "F.Cu" "F.Mask" "F.Paste")
			(net "P3V3_AUX")
		)
		(pad "2" smd circle
			(at 0.40005 0 90)
			(size 0 0)
			(layers "F.Cu" "F.Mask" "F.Paste")
			(net "SMB_P12V_HSC_SCL")
		)
	)
	(footprint ""
		(layer "F.Cu")
		(at 227.7745 -402.191982 90)
		(property "Reference" "PC2223"
			(at 0 0 90)
			(layer "F.SilkS")
			(hide yes)
			(effects
				(font
					(size 1.27 1.27)
				)
			)
		)
		(property "Value" ""
			(at 0 0 90)
			(layer "F.Fab")
			(effects
				(font
					(size 1.27 1.27)
				)
			)
		)
		(duplicate_pad_numbers_are_jumpers no)
		(fp_line
			(start 0.7874 -0.4064)
			(end 0.7874 0.4064)
			(stroke
				(width 0.1524)
				(type default)
			)
			(layer "F.SilkS")
		)
		(fp_line
			(start -0.7874 -0.4064)
			(end 0.7874 -0.4064)
			(stroke
				(width 0.1524)
				(type default)
			)
			(layer "F.SilkS")
		)
		(fp_line
			(start 0.7874 0.4064)
			(end -0.7874 0.4064)
			(stroke
				(width 0.1524)
				(type default)
			)
			(layer "F.SilkS")
		)
		(fp_line
			(start -0.7874 0.4064)
			(end -0.7874 -0.4064)
			(stroke
				(width 0.1524)
				(type default)
			)
			(layer "F.SilkS")
		)
		(fp_line
			(start -0.12065 -0.305054)
			(end -0.12065 -0.2794)
			(stroke
				(width 0.1)
				(type default)
			)
			(layer "F.Fab")
		)
		(fp_line
			(start -0.67945 -0.305054)
			(end -0.12065 -0.305054)
			(stroke
				(width 0.1)
				(type default)
			)
			(layer "F.Fab")
		)
		(fp_line
			(start 0.67945 -0.3048)
			(end 0.67945 0.3048)
			(stroke
				(width 0.1)
				(type default)
			)
			(layer "F.Fab")
		)
		(fp_line
			(start 0.12065 -0.3048)
			(end 0.67945 -0.3048)
			(stroke
				(width 0.1)
				(type default)
			)
			(layer "F.Fab")
		)
		(fp_line
			(start 0.12065 -0.2794)
			(end 0.12065 -0.3048)
			(stroke
				(width 0.1)
				(type default)
			)
			(layer "F.Fab")
		)
		(fp_line
			(start -0.12065 -0.2794)
			(end 0.12065 -0.2794)
			(stroke
				(width 0.1)
				(type default)
			)
			(layer "F.Fab")
		)
		(fp_line
			(start 0.120396 0.2794)
			(end -0.12065 0.2794)
			(stroke
				(width 0.1)
				(type default)
			)
			(layer "F.Fab")
		)
		(fp_line
			(start -0.12065 0.2794)
			(end -0.12065 0.3048)
			(stroke
				(width 0.1)
				(type default)
			)
			(layer "F.Fab")
		)
		(fp_line
			(start 0.67945 0.3048)
			(end 0.120396 0.3048)
			(stroke
				(width 0.1)
				(type default)
			)
			(layer "F.Fab")
		)
		(fp_line
			(start 0.120396 0.3048)
			(end 0.120396 0.2794)
			(stroke
				(width 0.1)
				(type default)
			)
			(layer "F.Fab")
		)
		(fp_line
			(start -0.12065 0.3048)
			(end -0.67945 0.3048)
			(stroke
				(width 0.1)
				(type default)
			)
			(layer "F.Fab")
		)
		(fp_line
			(start -0.67945 0.3048)
			(end -0.67945 -0.305054)
			(stroke
				(width 0.1)
				(type default)
			)
			(layer "F.Fab")
		)
		(pad "1" smd circle
			(at -0.40005 0 90)
			(size 0 0)
			(layers "F.Cu" "F.Mask" "F.Paste")
			(net "HSC_VDD_R_4")
		)
		(pad "2" smd circle
			(at 0.40005 0 90)
			(size 0 0)
			(layers "F.Cu" "F.Mask" "F.Paste")
			(net "AGND_HSC")
		)
	)
)
